FILE_TYPE = CONNECTIVITY;
{Allegro Design Entry HDL 17.4-2019 S026 (4007227) 1/17/2022}
"PAGE_NUMBER" = 55;
0"NC";
1"GND\g"$PHYS_NET_NAME"GND"VOLTAGE"0";
2"GND\g";
3"GND\g";
4"GND\g";
5"PVDD18_S5_P1\g";
6"GND\g";
7"GND\g";
8"GND\g";
9"GND\g";
10"FM_BMC_READY_N";
11"FM_BMC_TPM_PRES_N";
12"CPU1_PWRGD_OUT";
13"RST_CPU1_RSMRST_N";
14"TP_SLOT2_BUF_SKU_ID1";
15"XTAL_CPU1_X48M_X2_R";
16"XTAL_CPU1_X48M_X1";
17"IRQ_CPU_BMC_NMI_N";
18"CPU1_SPD_HOST_CTRL_R_N";
19"CPU1_SPD_HOST_CTRL_N";
20"CPU1_SPD_HOST_CTRL_N";
21"CLK_100M_CPU1_CLK04_R_DN";
22"CLK_100M_CPU1_CLK13_DN";
23"CLK_100M_CPU1_CLK13_DP";
24"CLK_100M_CPU1_CLK12_DN";
25"CLK_100M_CPU1_CLK13_R_DN";
26"CLK_100M_CPU1_CLK13_R_DP";
27"CLK_100M_CPU1_CLK11_DN";
28"CLK_100M_CPU1_CLK05_DN";
29"CLK_100M_CPU1_CLK11_DP";
30"CLK_100M_CPU1_CLK12_R_DN";
31"CLK_100M_CPU1_CLK12_R_DP";
32"CLK_100M_CPU1_CLK11_R_DN";
33"CLK_100M_CPU1_CLK11_R_DP";
34"PVDD18_S5_P1\g";
35"PVDD18_S5_P1\g";
36"PVDD11_S3_P1\g";
37"CLK_100M_CPU1_CLK12_DP";
38"CLK_100M_CPU1_CLK05_R_DN";
39"CLK_100M_CPU1_CLK05_DP";
40"CLK_100M_CPU1_CLK05_R_DP";
41"CLK_100M_CPU1_CLK04_R_DP";
42"CLK_100M_CPU1_CLK02_R_DN";
43"CLK_100M_CPU1_CLK03_R_DN";
44"CLK_100M_CPU1_CLK04_DN";
45"CLK_100M_CPU1_CLK04_DP";
46"XTAL_CPU1_X48M_X2";
47"CPU1_FORCE_SELFREFRESH";
48"IRQ_CPU_BMC_NMI_N";
49"CPU1_FORCE_SELFREFRESH";
50"CPU1_NMI_SYNC_FLOOD_N";
51"RST_CPU1_RESETL_N";
52"RST_CPU1_SYS_N";
53"CPU1_SLP_S5_N";
54"CPU1_NV_SAVE_N";
55"CPU1_FORCE_SELFREFRESH";
56"CPU1_SMERR_N";
57"FM_CPU1_SLP_S3_N";
58"CPU1_SLP_S3_N";
59"FM_CPU1_SLP_S5_N";
60"CPU1_SLP_S5_N";
61"XTAL_CPU1_X32K_X2";
62"XTAL_CPU1_X32K_X1";
63"CLK_CPU0_RTCCLK";
64"RST_CPU1_RSMRST_N";
65"CPU1_PWR_GD_IN";
66"INT_CPU1_HP_UBM_N";
67"XTAL_CPU1_X48M_X2";
68"CLK_CPU1_RTCCLK";
69"RST_CPU1_RESETL_N";
70"PWRGD_CPU1_PWROK";
71"CLK_100M_REF_IN_DN";
72"CLK_100M_REF_IN_DP";
73"SMB_CPU1_SEC_SCL";
74"SMB_CPU1_SEC_SDA";
75"I3C_1_SPD_DDRGL_CPU1_R_SDA";
76"I3C_1_SPD_DDRGL_CPU1_R_SCL";
77"I3C_0_SPD_DDRAF_CPU1_R_SDA";
78"XTAL_CPU1_X32K_X1";
79"XTAL_CPU1_X32K_X2";
80"CPU1_NMI_SYNC_FLOOD_N";
81"XTAL_CPU1_X48M_X1";
82"RST_CPU1_SYS_N";
83"NC_CPU1_PWR_BTN_N";
84"I3C_0_SPD_DDRAF_CPU1_R_SCL";
85"RST_CPU1_PERST0_N";
86"RST_CPU1_PERST1_N";
87"CLK_100M_CPU1_CLK01_R_DP";
88"CLK_100M_CPU1_CLK02_R_DP";
89"CLK_100M_CPU1_CLK01_DP";
90"CLK_100M_CPU1_CLK01_DN";
91"CLK_100M_CPU1_CLK02_DP";
92"CLK_100M_CPU1_CLK02_DN";
93"CLK_100M_CPU1_CLK03_DP";
94"CLK_100M_CPU1_CLK03_DN";
95"XTAL_CPU1_R_X32K_X1";
96"XTAL_CPU1_R_X32K_X2";
97"CLK_100M_CPU1_CLK03_R_DP";
98"CLK_100M_CPU1_CLK01_R_DN";
99"CPU1_PWRGD_OUT";
100"IRQ_WAKE_N";
101"CPU1_NV_SAVE_N";
102"CPU1_SLP_S3_N";
103"FM_BMC_READY_N";
104"FM_BMC_TPM_PRES_N";
105"TP_SLOT2_BUF_SKU_ID0";
106"FM_CPU1_BMC_RST_N";
107"PWRGD_CPU1_PWROK";
108"CPU1_SMERR_N";
109"FM_CPU1_BMC_RST_N";
110"I3C_1_SPD_DDRGL_CPU1_R_SDA";
111"I3C_1_SPD_DDRGL_CPU1_R_SCL";
112"I3C_0_SPD_DDRAF_CPU1_R_SDA";
113"I3C_0_SPD_DDRAF_CPU1_R_SCL";
114"GND\g";
115"GND\g";
116"GND\g";
117"GND\g";
118"GND\g";
%"Q_RES"
"1","(-5525,1050)","0","pure_quanta","I10";
;
LOCATION"R571"
$SEC"1"
CDS_SEC"1"
PACK_TYPE"0402LF"
VALUE"10M"
TOLERANCE"1%"
MATERIAL"CHIP"
WATTAGE"1/16W"
CDS_LIB"pure_quanta"
PART_NUMBER"CS61002FB02";
"B"
$PN"2"15;
"A"
$PN"1"16;
%"UNIVERSAL_GND"
"1","(-5900,1250)","0","pure_quanta_power","I11";
;
CDS_LIB"pure_quanta_power"
HDL_POWER"GND";
"A"1;
%"Q_XTAL_4P_13BI_24GND"
"1","(-5525,1575)","0","pure_quanta","I12";
;
LOCATION"Y4"
$SEC"1"
CDS_SEC"1"
VALUE"48MHZ"
PART_TYPE"SMLF"
MATERIAL"MISC"
CDS_LMAN_SYM_OUTLINE"-125,175,125,-175"
PIN_NAMES_ROTATE"True"
CDS_LIB"pure_quanta"
PART_NUMBER"BG648000076";
"X2"
$PN"3"15;
"G2"
$PN"4"2;
"G1"
$PN"2"1;
"X1"
$PN"1"16;
%"UNIVERSAL_GND"
"1","(-5125,1250)","0","pure_quanta_power","I13";
;
CDS_LIB"pure_quanta_power"
HDL_POWER"GND";
"A"2;
%"UNIVERSAL_GND"
"1","(-4900,525)","0","pure_quanta_power","I14";
;
CDS_LIB"pure_quanta_power"
HDL_POWER"GND";
"A"3;
%"Q_CAP"
"1","(-4900,825)","0","pure_quanta","I15";
;
LOCATION"C237"
$SEC"1"
CDS_SEC"1"
TOLERANCE"0.1PF"
VOLTAGE"50V"
MATERIAL"NPO"
PACK_TYPE"C0402"
VALUE"2.7PF"
CDS_LIB"pure_quanta"
PART_NUMBER"CH-276B0B00";
"B"
$PN"2"3;
"A"
$PN"1"15;
%"GENOA_SP5"
"21","(-4375,4475)","0","pure_quanta","I182";
;
LOCATION"U26"
$SEC"21"
CDS_SEC"21"
PART_TYPE"SMLF"
MATERIAL"IO"
VALUE"SOCKET6096_13568-001"
NEEDS_NO_SIZE"TRUE"
CDS_LMAN_SYM_OUTLINE"-1100,1800,1100,-1800"
CDS_LIB"pure_quanta"
PART_NUMBER"DGA^6000030";
"AGPIO7"
$PN"DH4"0;
"NMI_SYNC_FLOOD_L"
$PN"DJ31"80;
"SEC_SCL||AGPIO262"
$PN"B14"73;
"SEC_SDA||AGPIO263"
$PN"D14"74;
"AGPIO257||SGPIO1_CLK||CLK_REQ01_L"
$PN"C14"0;
"PWROK||SVI_RST_L"
$PN"D69"70;
"AGPIO6||DEVSLP1||SATA_ZP1_L"
$PN"DE40"103;
"AGPIO5||DEVSLP0||SATA_ZP0_L"
$PN"DF40"17;
"GENINT_L||PM_INTR_L||UBM_CPRSNT_CHANGE_DET_L||AGPIO89"
$PN"DJ35"66;
"AGPIO22"
$PN"DE32"14;
"AGPIO88"
$PN"DJ29"0;
"AGPIO21"
$PN"DF33"105;
"AGPIO87"
$PN"DG11"0;
"AGPIO109"
$PN"DG32"0;
"AGPIO107"
$PN"DG31"0;
"AGPIO106"
$PN"DF31"0;
"AGPIO105"
$PN"DE30"0;
"AGPIO104"
$PN"DH30"0;
"RESET_L \B"
$PN"B67"69;
"REFCLK100SSC_N||GPP_CLK10N"
$PN"A20"71;
"REFCLK100SSC_P||GPP_CLK10P"
$PN"A19"72;
"SMERR_L||AGPIO24"
$PN"DJ11"56;
"I2C5_SDA||BMC_SDA||SMBUS1_SDA||AGPIO20"
$PN"DJ20"0;
"I2C5_SCL||BMC_SCL||SMBUS1_SCL||AGPIO19"
$PN"DJ21"0;
"I2C4_SDA||HP_SDA||UBM_SDA||AGPIO14"
$PN"DH12"0;
"I2C4_SCL||HP_SCL||UBM_SCL||AGPIO13"
$PN"DG12"0;
"I3C3_SCL||I2C3_SCL||SPD3_SCL||AGPIO151"
$PN"A4"0;
"I3C1_SDA||I2C1_SDA||SPD1_SDA||AGPIO148"
$PN"A5"75;
"AGPIO116||CLK_REQ12_L"
$PN"DH15"106;
"PWRGD_OUT||AGPIO12"
$PN"DH36"99;
"AGPIO259||SGPIO3_CLK"
$PN"B16"0;
"I3C0_SCL||I2C0_SCL||SPD0_SCL||SMBUS0_SCL||AGPIO145"
$PN"A71"84;
"I3C2_SCL||I2C2_SCL||SPD2_SCL||AGPIO149"
$PN"C72"0;
"I3C1_SCL||I2C1_SCL||SPD1_SCL||AGPIO147"
$PN"C7"76;
"I3C0_SDA||I2C0_SDA||SPD0_SDA||SMBUS0_SDA||AGPIO146"
$PN"B71"77;
"AGPIO115||CLK_REQ11_L"
$PN"DH16"104;
"PCIE_RST0_L||AGPIO266"
$PN"D18"85;
"AGPIO256||SGPIO0_CLK"
$PN"A14"0;
"AGPIO258||SGPIO2_CLK||CLK_REQ02_L"
$PN"A13"0;
"I3C3_SDA||I2C3_SDA||SPD3_SDA||AGPIO152"
$PN"B4"0;
"SGPIO_DATAOUT||AGPIO260"
$PN"D15"0;
"I3C2_SDA||I2C2_SDA||SPD2_SDA||AGPIO150"
$PN"B72"0;
"SGPIO_LOAD||AGPIO261"
$PN"B15"0;
"PCIE_RST1_L||AGPIO26"
$PN"DG36"86;
"AGPIO3||SPD_HOST_CTRL_L"
$PN"DE36"18;
"AGPIO4||SATA_ACT_L"
$PN"DF36"0;
"GPP_CLK11P"
$PN"DJ41"33;
"GPP_CLK01P"
$PN"A8"87;
"GPP_CLK12P"
$PN"DJ45"31;
"GPP_CLK02P"
$PN"B6"88;
"GPP_CLK11N"
$PN"DJ42"32;
"GPP_CLK13P"
$PN"DJ53"26;
"GPP_CLK01N"
$PN"A7"98;
"GPP_CLK03P"
$PN"A10"97;
"GPP_CLK12N"
$PN"DJ44"30;
"GPP_CLK14P"
$PN"DJ48"0;
"GPP_CLK02N"
$PN"C6"42;
"GPP_CLK04P"
$PN"B12"41;
"GPP_CLK13N"
$PN"DJ54"25;
"GPP_CLK15P"
$PN"DJ51"0;
"GPP_CLK03N"
$PN"A11"43;
"GPP_CLK05P"
$PN"B9"40;
"GPP_CLK14N"
$PN"DJ47"0;
"GPP_CLK04N"
$PN"C12"21;
"GPP_CLK15N"
$PN"DJ50"0;
"GPP_CLK05N"
$PN"C9"38;
"RTCCLK"
$PN"DH9"68;
"FORCE_SELFREFRESH"
$PN"B63"55;
"NV_SAVE_L"
$PN"B64"101;
"PWR_BTN_L||AGPIO0"
$PN"DH7"83;
"X48M_X2"
$PN"DJ16"67;
"X48M_X1"
$PN"DJ17"81;
"X32K_X2"
$PN"DJ13"79;
"X32K_X1"
$PN"DJ14"78;
"WAKE_L||AGPIO2"
$PN"DJ10"100;
"SYS_RESET_L||AGPIO1"
$PN"DH6"82;
"SLP_S5_L"
$PN"DG4"60;
"SLP_S3_L"
$PN"DJ5"58;
"RSMRST_L \B"
$PN"DG10"64;
"PWR_GOOD"
$PN"DJ8"65;
%"UNIVERSAL_GND"
"1","(-6175,525)","0","pure_quanta_power","I2";
;
CDS_LIB"pure_quanta_power"
HDL_POWER"GND";
"A"4;
%"Q_RES"
"1","(-6900,3475)","0","pure_quanta","I236";
;
LOCATION"R570"
$SEC"1"
CDS_SEC"1"
VALUE"0"
PACK_TYPE"0402LF"
TOLERANCE"5%"
MATERIAL"CHIP"
WATTAGE"1/16W"
CDS_LIB"pure_quanta"
PART_NUMBER"CS00002JB13";
"B"
$PN"2"18;
"A"
$PN"1"19;
%"Q_RES"
"1","(-2250,2175)","0","pure_quanta","I24";
;
LOCATION"R574"
$SEC"1"
CDS_SEC"1"
VALUE"0"
MATERIAL"EMPTY"
PACK_TYPE"0402LF"
TOLERANCE"5%"
WATTAGE"1/16W"
CDS_LIB"pure_quanta"
PART_NUMBER"CS00002JB13";
"B"
$PN"2"62;
"A"
$PN"1"95;
%"Q_RES"
"1","(-2250,2425)","0","pure_quanta","I26";
;
LOCATION"R573"
$SEC"1"
CDS_SEC"1"
VALUE"0"
MATERIAL"CHIP"
PACK_TYPE"0402LF"
TOLERANCE"5%"
WATTAGE"1/16W"
CDS_LIB"pure_quanta"
PART_NUMBER"CS00002JB13";
"B"
$PN"2"62;
"A"
$PN"1"63;
%"UNIVERSAL_POWER"
"1","(-7375,4975)","2","pure_quanta_power","I291";
;
HDL_POWER"PVDD18_S5_P1"
CDS_LIB"pure_quanta_power";
"A"5;
%"Q_RES"
"1","(-7050,4875)","0","pure_quanta","I292";
;
LOCATION"R1424"
$SEC"1"
CDS_SEC"1"
VALUE"2.2K"
CDS_LIB"pure_quanta"
WATTAGE"1/16W"
MATERIAL"CHIP"
TOLERANCE"5%"
PACK_TYPE"0402LF"
PART_NUMBER"CS22202JB07";
"B"
$PN"2"66;
"A"
$PN"1"5;
%"Q_RES"
"1","(-2250,2125)","0","pure_quanta","I296";
;
LOCATION"R575"
$SEC"1"
CDS_SEC"1"
VALUE"0"
MATERIAL"EMPTY"
PACK_TYPE"0402LF"
TOLERANCE"5%"
WATTAGE"1/16W"
CDS_LIB"pure_quanta"
PART_NUMBER"CS00002JB13";
"B"
$PN"2"61;
"A"
$PN"1"96;
%"Q_RES"
"1","(-6625,5775)","0","pure_quanta","I297";
;
LOCATION"R191"
$SEC"1"
CDS_SEC"1"
MATERIAL"EMPTY"
VALUE"0"
BOM_COST"MEM"
CDS_LIB"pure_quanta"
WATTAGE"1/16W"
TOLERANCE"5%"
PACK_TYPE"0402LF"
PART_NUMBER"CS00002JB13";
"B"
$PN"2"60;
"A"
$PN"1"59;
%"Q_RES"
"1","(-6625,5725)","0","pure_quanta","I298";
;
LOCATION"R192"
$SEC"1"
CDS_SEC"1"
MATERIAL"EMPTY"
VALUE"0"
BOM_COST"MEM"
CDS_LIB"pure_quanta"
WATTAGE"1/16W"
TOLERANCE"5%"
PACK_TYPE"0402LF"
PART_NUMBER"CS00002JB13";
"B"
$PN"2"58;
"A"
$PN"1"57;
%"Q_CAP"
"1","(-6175,825)","0","pure_quanta","I3";
;
LOCATION"C236"
$SEC"1"
CDS_SEC"1"
PACK_TYPE"C0402"
TOLERANCE"0.1PF"
VOLTAGE"50V"
MATERIAL"NPO"
VALUE"2.7PF"
CDS_LIB"pure_quanta"
PART_NUMBER"CH-276B0B00";
"B"
$PN"2"4;
"A"
$PN"1"16;
%"Q_RES"
"1","(-2000,4175)","0","pure_quanta","I302";
;
LOCATION"R3352"
$SEC"1"
CDS_SEC"1"
VALUE"0"
WATTAGE"1/16W"
MATERIAL"CHIP"
TOLERANCE"5%"
PACK_TYPE"0402LF"
CDS_LIB"pure_quanta"
PART_NUMBER"CS00002JB13";
"B"
$PN"2"29;
"A"
$PN"1"33;
%"Q_RES"
"1","(-2000,4125)","0","pure_quanta","I303";
;
LOCATION"R3353"
$SEC"1"
CDS_SEC"1"
VALUE"0"
WATTAGE"1/16W"
TOLERANCE"5%"
PACK_TYPE"0402LF"
MATERIAL"CHIP"
CDS_LIB"pure_quanta"
PART_NUMBER"CS00002JB13";
"B"
$PN"2"27;
"A"
$PN"1"32;
%"Q_RES"
"1","(-2000,4875)","0","pure_quanta","I306";
;
LOCATION"R3355"
$SEC"1"
CDS_SEC"1"
PACK_TYPE"0402LF"
VALUE"0"
WATTAGE"1/16W"
TOLERANCE"5%"
MATERIAL"CHIP"
CDS_LIB"pure_quanta"
PART_NUMBER"CS00002JB13";
"B"
$PN"2"90;
"A"
$PN"1"98;
%"Q_RES"
"1","(-2000,4925)","0","pure_quanta","I307";
;
LOCATION"R3354"
$SEC"1"
CDS_SEC"1"
PACK_TYPE"0402LF"
VALUE"0"
TOLERANCE"5%"
MATERIAL"CHIP"
WATTAGE"1/16W"
CDS_LIB"pure_quanta"
PART_NUMBER"CS00002JB13";
"B"
$PN"2"89;
"A"
$PN"1"87;
%"Q_RES"
"1","(-2000,4775)","0","pure_quanta","I308";
;
LOCATION"R3194"
$SEC"1"
CDS_SEC"1"
MATERIAL"CHIP"
PACK_TYPE"0402LF"
VALUE"0"
WATTAGE"1/16W"
TOLERANCE"5%"
CDS_LIB"pure_quanta"
PART_NUMBER"CS00002JB13";
"B"
$PN"2"91;
"A"
$PN"1"88;
%"Q_RES"
"1","(-2000,4725)","0","pure_quanta","I309";
;
LOCATION"R3195"
$SEC"1"
CDS_SEC"1"
TOLERANCE"5%"
PACK_TYPE"0402LF"
WATTAGE"1/16W"
VALUE"0"
MATERIAL"CHIP"
CDS_LIB"pure_quanta"
PART_NUMBER"CS00002JB13";
"B"
$PN"2"92;
"A"
$PN"1"42;
%"Q_RES"
"1","(-2000,4625)","0","pure_quanta","I312";
;
LOCATION"R3196"
$SEC"1"
CDS_SEC"1"
TOLERANCE"5%"
MATERIAL"CHIP"
VALUE"0"
PACK_TYPE"0402LF"
WATTAGE"1/16W"
CDS_LIB"pure_quanta"
PART_NUMBER"CS00002JB13";
"B"
$PN"2"93;
"A"
$PN"1"97;
%"Q_RES"
"1","(-2000,4575)","0","pure_quanta","I313";
;
LOCATION"R3197"
$SEC"1"
CDS_SEC"1"
VALUE"0"
TOLERANCE"5%"
PACK_TYPE"0402LF"
WATTAGE"1/16W"
MATERIAL"CHIP"
CDS_LIB"pure_quanta"
PART_NUMBER"CS00002JB13";
"B"
$PN"2"94;
"A"
$PN"1"43;
%"Q_RES"
"1","(-2000,4475)","0","pure_quanta","I316";
;
LOCATION"R3198"
$SEC"1"
CDS_SEC"1"
WATTAGE"1/16W"
MATERIAL"CHIP"
VALUE"0"
PACK_TYPE"0402LF"
TOLERANCE"5%"
CDS_LIB"pure_quanta"
PART_NUMBER"CS00002JB13";
"B"
$PN"2"45;
"A"
$PN"1"41;
%"Q_RES"
"1","(-2000,4425)","0","pure_quanta","I317";
;
LOCATION"R3199"
$SEC"1"
CDS_SEC"1"
PACK_TYPE"0402LF"
VALUE"0"
TOLERANCE"5%"
WATTAGE"1/16W"
MATERIAL"CHIP"
CDS_LIB"pure_quanta"
PART_NUMBER"CS00002JB13";
"B"
$PN"2"44;
"A"
$PN"1"21;
%"Q_RES"
"1","(-2000,4325)","0","pure_quanta","I320";
;
LOCATION"R3200"
$SEC"1"
CDS_SEC"1"
MATERIAL"CHIP"
WATTAGE"1/16W"
VALUE"0"
TOLERANCE"5%"
PACK_TYPE"0402LF"
CDS_LIB"pure_quanta"
PART_NUMBER"CS00002JB13";
"B"
$PN"2"39;
"A"
$PN"1"40;
%"Q_RES"
"1","(-2000,4275)","0","pure_quanta","I321";
;
LOCATION"R3201"
$SEC"1"
CDS_SEC"1"
WATTAGE"1/16W"
TOLERANCE"5%"
VALUE"0"
PACK_TYPE"0402LF"
MATERIAL"CHIP"
CDS_LIB"pure_quanta"
PART_NUMBER"CS00002JB13";
"B"
$PN"2"28;
"A"
$PN"1"38;
%"Q_RES"
"1","(-2000,3975)","0","pure_quanta","I326";
;
LOCATION"R4306"
$SEC"1"
CDS_SEC"1"
PACK_TYPE"0402LF"
VALUE"0"
TOLERANCE"5%"
WATTAGE"1/16W"
MATERIAL"CHIP"
CDS_LIB"pure_quanta"
PART_NUMBER"CS00002JB13";
"B"
$PN"2"24;
"A"
$PN"1"30;
%"Q_RES"
"1","(-2000,4025)","0","pure_quanta","I327";
;
LOCATION"R4305"
$SEC"1"
CDS_SEC"1"
MATERIAL"CHIP"
PACK_TYPE"0402LF"
WATTAGE"1/16W"
TOLERANCE"5%"
VALUE"0"
CDS_LIB"pure_quanta"
PART_NUMBER"CS00002JB13";
"B"
$PN"2"37;
"A"
$PN"1"31;
%"UNIVERSAL_GND"
"1","(-9100,275)","0","pure_quanta_power","I328";
;
CDS_LIB"pure_quanta_power"
HDL_POWER"GND";
"A"118;
%"UNIVERSAL_GND"
"1","(-8975,275)","0","pure_quanta_power","I329";
;
CDS_LIB"pure_quanta_power"
HDL_POWER"GND";
"A"117;
%"Q_RES"
"1","(-9100,425)","1","pure_quanta","I330";
;
LOCATION"R5032"
$SEC"1"
CDS_SEC"1"
MATERIAL"EMPTY"
VALUE"4.7K"
PACK_TYPE"0402LF"
TOLERANCE"5%"
WATTAGE"1/16W"
CDS_LIB"pure_quanta"
PART_NUMBER"CS24702JB10";
"B"
$PN"2"48;
"A"
$PN"1"118;
%"Q_RES"
"1","(-8975,425)","1","pure_quanta","I331";
;
LOCATION"R5031"
$SEC"1"
CDS_SEC"1"
MATERIAL"EMPTY"
VALUE"4.7K"
PACK_TYPE"0402LF"
TOLERANCE"5%"
WATTAGE"1/16W"
CDS_LIB"pure_quanta"
PART_NUMBER"CS24702JB10";
"B"
$PN"2"10;
"A"
$PN"1"117;
%"UNIVERSAL_GND"
"1","(-8850,275)","0","pure_quanta_power","I332";
;
CDS_LIB"pure_quanta_power"
HDL_POWER"GND";
"A"116;
%"UNIVERSAL_GND"
"1","(-8700,275)","0","pure_quanta_power","I333";
;
CDS_LIB"pure_quanta_power"
HDL_POWER"GND";
"A"115;
%"Q_RES"
"1","(-8850,425)","1","pure_quanta","I334";
;
LOCATION"R5030"
$SEC"1"
CDS_SEC"1"
MATERIAL"EMPTY"
VALUE"4.7K"
PACK_TYPE"0402LF"
TOLERANCE"5%"
WATTAGE"1/16W"
CDS_LIB"pure_quanta"
PART_NUMBER"CS24702JB10";
"B"
$PN"2"11;
"A"
$PN"1"116;
%"Q_RES"
"1","(-8700,425)","1","pure_quanta","I335";
;
LOCATION"R491"
$SEC"1"
CDS_SEC"1"
VALUE"4.7K"
MATERIAL"EMPTY"
PACK_TYPE"0402LF"
TOLERANCE"5%"
WATTAGE"1/16W"
CDS_LIB"pure_quanta"
PART_NUMBER"CS24702JB10";
"B"
$PN"2"12;
"A"
$PN"1"115;
%"Q_RES"
"1","(-9100,1150)","1","pure_quanta","I336";
;
LOCATION"R544"
$SEC"1"
CDS_SEC"1"
MATERIAL"CHIP"
VALUE"4.7K"
PACK_TYPE"0402LF"
TOLERANCE"5%"
WATTAGE"1/16W"
CDS_LIB"pure_quanta"
PART_NUMBER"CS24702JB10";
"B"
$PN"2"34;
"A"
$PN"1"48;
%"Q_RES"
"1","(-8975,1150)","1","pure_quanta","I337";
;
LOCATION"R545"
$SEC"1"
CDS_SEC"1"
VALUE"4.7K"
MATERIAL"CHIP"
PACK_TYPE"0402LF"
TOLERANCE"5%"
WATTAGE"1/16W"
CDS_LIB"pure_quanta"
PART_NUMBER"CS24702JB10";
"B"
$PN"2"34;
"A"
$PN"1"10;
%"Q_RES"
"1","(-8850,1150)","1","pure_quanta","I338";
;
LOCATION"R546"
$SEC"1"
CDS_SEC"1"
VALUE"4.7K"
MATERIAL"CHIP"
PACK_TYPE"0402LF"
TOLERANCE"5%"
WATTAGE"1/16W"
CDS_LIB"pure_quanta"
PART_NUMBER"CS24702JB10";
"B"
$PN"2"34;
"A"
$PN"1"11;
%"Q_RES"
"1","(-8700,1150)","1","pure_quanta","I339";
;
LOCATION"R456"
$SEC"1"
CDS_SEC"1"
MATERIAL"EMPTY"
VALUE"4.7K"
CDS_LIB"pure_quanta"
WATTAGE"1/16W"
TOLERANCE"5%"
PACK_TYPE"0402LF"
PART_NUMBER"CS24702JB10";
"B"
$PN"2"34;
"A"
$PN"1"12;
%"UNIVERSAL_GND"
"1","(-8475,275)","0","pure_quanta_power","I340";
;
CDS_LIB"pure_quanta_power"
HDL_POWER"GND";
"A"114;
%"Q_RES"
"1","(-8475,425)","1","pure_quanta","I341";
;
LOCATION"R584"
$SEC"1"
CDS_SEC"1"
MATERIAL"EMPTY"
VALUE"4.7K"
CDS_LIB"pure_quanta"
WATTAGE"1/16W"
TOLERANCE"5%"
PACK_TYPE"0402LF"
PART_NUMBER"CS24702JB10";
"B"
$PN"2"13;
"A"
$PN"1"114;
%"Q_RES"
"1","(-8475,1150)","1","pure_quanta","I342";
;
LOCATION"R583"
$SEC"1"
CDS_SEC"1"
VALUE"4.7K"
MATERIAL"EMPTY"
CDS_LIB"pure_quanta"
WATTAGE"1/16W"
TOLERANCE"5%"
PACK_TYPE"0402LF"
PART_NUMBER"CS24702JB10";
"B"
$PN"2"34;
"A"
$PN"1"13;
%"UNIVERSAL_POWER"
"1","(-8700,1350)","0","pure_quanta_power","I343";
;
HDL_POWER"PVDD18_S5_P1"
CDS_LIB"pure_quanta_power";
"A"34;
%"Q_RES"
"1","(-8625,1700)","2","pure_quanta","I352";
;
LOCATION"R548"
$SEC"1"
CDS_SEC"1"
VALUE"4.7K"
MATERIAL"EMPTY"
PACK_TYPE"0402LF"
TOLERANCE"5%"
WATTAGE"1/16W"
CDS_LIB"pure_quanta"
PART_NUMBER"CS24702JB10";
"B"
$PN"2"35;
"A"
$PN"1"53;
%"Q_RES"
"1","(-8625,1650)","2","pure_quanta","I353";
;
LOCATION"R549"
$SEC"1"
CDS_SEC"1"
VALUE"4.7K"
MATERIAL"EMPTY"
PACK_TYPE"0402LF"
TOLERANCE"5%"
WATTAGE"1/16W"
CDS_LIB"pure_quanta"
PART_NUMBER"CS24702JB10";
"B"
$PN"2"35;
"A"
$PN"1"102;
%"Q_RES"
"1","(-8625,1850)","0","pure_quanta","I355";
;
LOCATION"R562"
$SEC"1"
CDS_SEC"1"
VALUE"2.2K"
CDS_LIB"pure_quanta"
WATTAGE"1/16W"
MATERIAL"CHIP"
TOLERANCE"5%"
PACK_TYPE"0402LF"
PART_NUMBER"CS22202JB07";
"B"
$PN"2"50;
"A"
$PN"1"35;
%"Q_RES"
"1","(-8625,1900)","0","pure_quanta","I356";
;
LOCATION"R559"
$SEC"1"
CDS_SEC"1"
VALUE"2.2K"
CDS_LIB"pure_quanta"
WATTAGE"1/16W"
MATERIAL"CHIP"
TOLERANCE"5%"
PACK_TYPE"0402LF"
PART_NUMBER"CS22202JB07";
"B"
$PN"2"52;
"A"
$PN"1"35;
%"Q_RES"
"1","(-8625,2000)","0","pure_quanta","I357";
;
LOCATION"R556"
$SEC"1"
CDS_SEC"1"
MATERIAL"EMPTY"
VALUE"1K"
PACK_TYPE"0402LF"
WATTAGE"1/16W"
CDS_LIB"pure_quanta"
TOLERANCE"1%"
PART_NUMBER"CS21002FB06";
"B"
$PN"2"51;
"A"
$PN"1"35;
%"Q_RES"
"1","(-8625,2050)","2","pure_quanta","I359";
;
LOCATION"R553"
$SEC"1"
CDS_SEC"1"
VALUE"4.7K"
PACK_TYPE"0402LF"
TOLERANCE"5%"
MATERIAL"CHIP"
WATTAGE"1/16W"
CDS_LIB"pure_quanta"
PART_NUMBER"CS24702JB10";
"B"
$PN"2"35;
"A"
$PN"1"54;
%"Q_RES"
"1","(-8625,2100)","2","pure_quanta","I360";
;
LOCATION"R551"
$SEC"1"
CDS_SEC"1"
VALUE"4.7K"
PACK_TYPE"0402LF"
TOLERANCE"5%"
MATERIAL"CHIP"
WATTAGE"1/16W"
CDS_LIB"pure_quanta"
PART_NUMBER"CS24702JB10";
"B"
$PN"2"35;
"A"
$PN"1"20;
%"UNIVERSAL_POWER"
"1","(-8975,2500)","2","pure_quanta_power","I361";
;
HDL_POWER"PVDD18_S5_P1"
CDS_LIB"pure_quanta_power";
"A"35;
%"Q_RES"
"1","(-8625,2250)","2","pure_quanta","I362";
;
LOCATION"R547"
$SEC"1"
CDS_SEC"1"
VALUE"4.7K"
PACK_TYPE"0402LF"
TOLERANCE"5%"
MATERIAL"CHIP"
WATTAGE"1/16W"
CDS_LIB"pure_quanta"
PART_NUMBER"CS24702JB10";
"B"
$PN"2"35;
"A"
$PN"1"109;
%"Q_RES"
"1","(-8625,2150)","2","pure_quanta","I363";
;
LOCATION"R550"
$SEC"1"
CDS_SEC"1"
VALUE"4.7K"
PACK_TYPE"0402LF"
TOLERANCE"5%"
MATERIAL"CHIP"
WATTAGE"1/16W"
CDS_LIB"pure_quanta"
PART_NUMBER"CS24702JB10";
"B"
$PN"2"35;
"A"
$PN"1"108;
%"Q_RES"
"1","(-8625,2200)","0","pure_quanta","I364";
;
LOCATION"R557"
$SEC"1"
CDS_SEC"1"
VALUE"1K"
MATERIAL"EMPTY"
CDS_LIB"pure_quanta"
WATTAGE"1/16W"
PACK_TYPE"0402LF"
TOLERANCE"1%"
PART_NUMBER"CS21002FB06";
"B"
$PN"2"107;
"A"
$PN"1"35;
%"Q_RES"
"2","(-9050,3000)","0","pure_quanta","I365";
;
LOCATION"R541"
$SEC"1"
CDS_SEC"1"
VALUE"1K"
MATERIAL"EMPTY"
TOLERANCE"1%"
PACK_TYPE"0402LF"
WATTAGE"1/16W"
CDS_LIB"pure_quanta"
PART_NUMBER"CS21002FB06";
"A"
$PN"1"36;
"B"
$PN"2"110;
%"Q_RES"
"2","(-8875,3000)","0","pure_quanta","I366";
;
LOCATION"R542"
$SEC"1"
CDS_SEC"1"
MATERIAL"EMPTY"
VALUE"1K"
TOLERANCE"1%"
PACK_TYPE"0402LF"
WATTAGE"1/16W"
CDS_LIB"pure_quanta"
PART_NUMBER"CS21002FB06";
"A"
$PN"1"36;
"B"
$PN"2"111;
%"Q_RES"
"2","(-8700,3000)","0","pure_quanta","I367";
;
LOCATION"R543"
$SEC"1"
CDS_SEC"1"
VALUE"1K"
MATERIAL"EMPTY"
TOLERANCE"1%"
PACK_TYPE"0402LF"
WATTAGE"1/16W"
CDS_LIB"pure_quanta"
PART_NUMBER"CS21002FB06";
"A"
$PN"1"36;
"B"
$PN"2"112;
%"Q_RES"
"2","(-8525,3000)","0","pure_quanta","I368";
;
LOCATION"R563"
$SEC"1"
CDS_SEC"1"
MATERIAL"EMPTY"
VALUE"1K"
TOLERANCE"1%"
CDS_LIB"pure_quanta"
WATTAGE"1/16W"
PACK_TYPE"0402LF"
PART_NUMBER"CS21002FB06";
"A"
$PN"1"36;
"B"
$PN"2"113;
%"VCC_CORE"
"1","(-8525,3300)","0","pure_quanta_power","I369";
;
HDL_POWER"PVDD11_S3_P1"
CDS_LIB"pure_quanta_power";
"A"36;
%"Q_RES"
"2","(-4900,1900)","2","pure_quanta","I386";
;
LOCATION"R5103"
$SEC"1"
CDS_SEC"1"
VALUE"49.9"
TOLERANCE"1%"
WATTAGE"1/16W"
PACK_TYPE"0402LF"
MATERIAL"CHIP"
CDS_LIB"pure_quanta"
PART_NUMBER"CS04992FB07";
"A"
$PN"1"46;
"B"
$PN"2"15;
%"UNIVERSAL_GND"
"1","(-7400,5150)","0","pure_quanta_power","I387";
;
CDS_LIB"pure_quanta_power"
HDL_POWER"GND";
"A"6;
%"Q_CAP"
"1","(-7400,5350)","0","pure_quanta","I388";
;
LOCATION"C5024"
$SEC"1"
CDS_SEC"1"
PACK_TYPE"0402"
MATERIAL"X7R"
TOLERANCE"5%"
VOLTAGE"50V"
VALUE"1000PF"
CDS_LIB"pure_quanta"
PART_NUMBER"TMP_QCH21006JB10";
"B"
$PN"2"6;
"A"
$PN"1"64;
%"Q_RES"
"1","(-3625,1450)","0","pure_quanta","I389";
;
LOCATION"R572"
SEC"1"
MATERIAL"CHIP"
WATTAGE"1/16W"
PACK_TYPE"0402LF"
VALUE"20M"
TOLERANCE"1%"
CDS_LIB"pure_quanta"
SEC_TYPE"0402LF"
PART_NUMBER"CS62002FB01";
"B"
$PN"2"96;
"A"
$PN"1"95;
%"Q_RES"
"1","(-8625,1950)","2","pure_quanta","I390";
;
LOCATION"R558"
SEC"1"
VALUE"4.7K"
MATERIAL"EMPTY"
WATTAGE"1/16W"
TOLERANCE"5%"
CDS_LIB"pure_quanta"
SEC_TYPE"0402LF"
PACK_TYPE"0402LF"
PART_NUMBER"CS24702JB10";
"B"
$PN"2"35;
"A"
$PN"1"49;
%"Q_RES"
"2","(-8275,475)","0","pure_quanta","I392";
;
LOCATION"R6503"
$SEC"1"
CDS_SEC"1"
VALUE"2.2K"
MATERIAL"CHIP"
PACK_TYPE"0402LF"
TOLERANCE"5%"
WATTAGE"1/16W"
CDS_LIB"pure_quanta"
PART_NUMBER"CS22202JB07";
"A"
$PN"1"47;
"B"
$PN"2"7;
%"UNIVERSAL_GND"
"1","(-8275,225)","0","pure_quanta_power","I393";
;
CDS_LIB"pure_quanta_power"
HDL_POWER"GND";
"A"7;
%"Q_RES"
"1","(-2000,3825)","0","pure_quanta","I394";
;
LOCATION"R8351"
$SEC"1"
CDS_SEC"1"
TOLERANCE"5%"
VALUE"0"
WATTAGE"1/16W"
PACK_TYPE"0402LF"
CDS_LIB"pure_quanta"
MATERIAL"CHIP"
PART_NUMBER"CS00002JB13";
"B"
$PN"2"22;
"A"
$PN"1"25;
%"Q_RES"
"1","(-2000,3875)","0","pure_quanta","I397";
;
LOCATION"R8350"
$SEC"1"
CDS_SEC"1"
VALUE"0"
MATERIAL"CHIP"
WATTAGE"1/16W"
PACK_TYPE"0402LF"
TOLERANCE"5%"
CDS_LIB"pure_quanta"
PART_NUMBER"CS00002JB13";
"B"
$PN"2"23;
"A"
$PN"1"26;
%"UNIVERSAL_GND"
"1","(-4125,650)","0","pure_quanta_power","I4";
;
CDS_LIB"pure_quanta_power"
HDL_POWER"GND";
"A"8;
%"Q_CAP"
"1","(-4125,1050)","0","pure_quanta","I5";
;
LOCATION"C238"
$SEC"1"
CDS_SEC"1"
TOLERANCE"1%"
MATERIAL"NPO"
PACK_TYPE"0402"
VALUE"10PF"
VOLTAGE"50V"
CDS_LIB"pure_quanta"
PART_NUMBER"TMP_QCH0106F0B00";
"B"
$PN"2"8;
"A"
$PN"1"95;
%"Q_CRYSTAL"
"1","(-3625,1750)","0","pure_quanta","I7";
;
LOCATION"Y5"
$SEC"1"
CDS_SEC"1"
MATERIAL"EMPTY"
VALUE"32.768KHZ"
PACK_TYPE"SMLF"
CDS_LIB"pure_quanta"
NEEDS_NO_SIZE"TRUE"
PART_NUMBER"BG632768012";
"2"
$PN"2"96;
"1"
$PN"1"95;
%"UNIVERSAL_GND"
"1","(-3075,675)","0","pure_quanta_power","I8";
;
CDS_LIB"pure_quanta_power"
HDL_POWER"GND";
"A"9;
%"Q_CAP"
"1","(-3075,1075)","0","pure_quanta","I9";
;
LOCATION"C239"
$SEC"1"
CDS_SEC"1"
TOLERANCE"1%"
MATERIAL"NPO"
PACK_TYPE"0402"
VOLTAGE"50V"
VALUE"10PF"
CDS_LIB"pure_quanta"
PART_NUMBER"TMP_QCH0106F0B00";
"B"
$PN"2"9;
"A"
$PN"1"96;
END.
